(kicad_pcb
	(version 20260206)
	(generator "pcbnew")
	(generator_version "10.0")
	(general
		(thickness 1.6)
		(legacy_teardrops no)
	)
	(paper "A4")
	(title_block
		(title "Wiwynn_Tioga_Pass_MB.brd")
		(comment 1 "Tioga Pass / footprints 344-348 of 4770")
	)
	(layers
		(0 "F.Cu" signal "TOP")
		(4 "In1.Cu" signal "L2GND")
		(6 "In2.Cu" signal "L3")
		(8 "In3.Cu" signal "L4GND")
		(10 "In4.Cu" signal "L5")
		(12 "In5.Cu" signal "L6GND")
		(14 "In6.Cu" signal "L7VCC")
		(16 "In7.Cu" signal "L8VCC")
		(18 "In8.Cu" signal "L9GND")
		(20 "In9.Cu" signal "L10")
		(22 "In10.Cu" signal "L11GND")
		(24 "In11.Cu" signal "L12")
		(26 "In12.Cu" signal "L13GND")
		(2 "B.Cu" signal "BOTTOM")
		(9 "F.Adhes" user "F.Adhesive")
		(11 "B.Adhes" user "B.Adhesive")
		(13 "F.Paste" user "Package Geometry/Pastemask Top")
		(15 "B.Paste" user "Package Geometry/Pastemask Bottom")
		(5 "F.SilkS" user "Ref Des/Silkscreen Top")
		(7 "B.SilkS" user "Ref Des/Silkscreen Bottom")
		(1 "F.Mask" user "Board Geometry/Soldermask Top")
		(3 "B.Mask" user "Board Geometry/Soldermask Bottom")
		(17 "Dwgs.User" user "User.Drawings")
		(19 "Cmts.User" user "User.Comments")
		(21 "Eco1.User" user "User.Eco1")
		(23 "Eco2.User" user "User.Eco2")
		(25 "Edge.Cuts" user "Board Geometry/Outline")
		(27 "Margin" user)
		(31 "F.CrtYd" user "Package Geometry/Place Bound Top")
		(29 "B.CrtYd" user "Package Geometry/Place Bound Bottom")
		(35 "F.Fab" user "Ref Des/Assembly Top")
		(33 "B.Fab" user "Ref Des/Assembly Bottom")
	)
	(footprint ""
		(layer "F.Cu")
		(at 474.472 -147.5105 180)
		(property "Reference" "R1L16"
			(at 0 0 180)
			(layer "F.SilkS")
			(hide yes)
			(effects
				(font
					(size 1.27 1.27)
				)
			)
		)
		(property "Value" ""
			(at 0 0 180)
			(layer "F.Fab")
			(effects
				(font
					(size 1.27 1.27)
				)
			)
		)
		(duplicate_pad_numbers_are_jumpers no)
		(fp_poly
			(pts
				(xy -0.2794 -0.1016) (xy 0.2794 -0.1016) (xy 0.2794 0.9906) (xy -0.2794 0.9906)
			)
			(stroke
				(width 0)
				(type default)
			)
			(fill no)
			(layer "F.CrtYd")
		)
		(fp_line
			(start 0.2794 0.9906)
			(end 0.2794 -0.1016)
			(stroke
				(width 0.1)
				(type default)
			)
			(layer "F.Fab")
		)
		(fp_line
			(start 0.2794 -0.1016)
			(end -0.2794 -0.1016)
			(stroke
				(width 0.1)
				(type default)
			)
			(layer "F.Fab")
		)
		(fp_line
			(start -0.2794 0.9906)
			(end 0.2794 0.9906)
			(stroke
				(width 0.1)
				(type default)
			)
			(layer "F.Fab")
		)
		(fp_line
			(start -0.2794 -0.1016)
			(end -0.2794 0.9906)
			(stroke
				(width 0.1)
				(type default)
			)
			(layer "F.Fab")
		)
		(pad "1" smd rect
			(at 0 0 180)
			(size 0.508 0.508)
			(layers "F.Cu" "F.Mask" "F.Paste")
			(net "PWRGD_P3V3_R1")
		)
		(pad "2" smd rect
			(at 0 0.889 180)
			(size 0.508 0.508)
			(layers "F.Cu" "F.Mask" "F.Paste")
			(net "PWRGD_P3V3")
		)
		(zone
			(layer "F.Cu")
			(hatch none 0.5)
			(connect_pads
				(clearance 0)
			)
			(min_thickness 0.25)
			(keepout
				(tracks not_allowed)
				(vias allowed)
				(pads allowed)
				(copperpour not_allowed)
				(footprints allowed)
			)
			(placement
				(enabled no)
				(sheetname "")
			)
			(fill
				(thermal_gap 0.5)
				(thermal_bridge_width 0.5)
				(island_removal_mode 0)
			)
			(polygon
				(pts
					(xy 474.726 -148.1455) (xy 474.218 -148.1455) (xy 474.218 -147.7645) (xy 474.726 -147.7645)
				)
			)
		)
		(zone
			(layer "F.Cu")
			(hatch none 0.5)
			(connect_pads
				(clearance 0)
			)
			(min_thickness 0.25)
			(keepout
				(tracks allowed)
				(vias not_allowed)
				(pads allowed)
				(copperpour not_allowed)
				(footprints allowed)
			)
			(placement
				(enabled no)
				(sheetname "")
			)
			(fill
				(thermal_gap 0.5)
				(thermal_bridge_width 0.5)
				(island_removal_mode 0)
			)
			(polygon
				(pts
					(xy 474.726 -147.7645) (xy 474.218 -147.7645) (xy 474.218 -148.1455) (xy 474.726 -148.1455)
				)
			)
		)
	)
	(footprint ""
		(layer "F.Cu")
		(at 107.8611 -12.954 90)
		(property "Reference" "C3G1"
			(at 1.848866 0.752348 90)
			(unlocked yes)
			(layer "F.SilkS")
			(effects
				(font
					(size 1.27 0.9652)
					(thickness 0.1524)
				)
			)
		)
		(property "Value" ""
			(at 0 0 90)
			(layer "F.Fab")
			(effects
				(font
					(size 1.27 1.27)
				)
			)
		)
		(duplicate_pad_numbers_are_jumpers no)
		(fp_rect
			(start -0.500126 1.598422)
			(end 0.500126 -0.201422)
			(stroke
				(width 0)
				(type default)
			)
			(fill no)
			(layer "F.CrtYd")
		)
		(fp_line
			(start 0.500126 -0.201422)
			(end 0.500126 1.598422)
			(stroke
				(width 0.1)
				(type default)
			)
			(layer "F.Fab")
		)
		(fp_line
			(start -0.500126 -0.201422)
			(end 0.500126 -0.201422)
			(stroke
				(width 0.1)
				(type default)
			)
			(layer "F.Fab")
		)
		(fp_line
			(start 0.500126 1.598422)
			(end -0.500126 1.598422)
			(stroke
				(width 0.1)
				(type default)
			)
			(layer "F.Fab")
		)
		(fp_line
			(start -0.500126 1.598422)
			(end -0.500126 -0.201422)
			(stroke
				(width 0.1)
				(type default)
			)
			(layer "F.Fab")
		)
		(pad "1" smd rect
			(at 0 0)
			(size 0.889 0.9906)
			(layers "F.Cu" "F.Mask" "F.Paste")
			(net "PVDDQ_GHJ")
		)
		(pad "2" smd rect
			(at 0 1.397)
			(size 0.889 0.9906)
			(layers "F.Cu" "F.Mask" "F.Paste")
			(net "GND")
		)
		(zone
			(layer "F.Cu")
			(hatch none 0.5)
			(connect_pads
				(clearance 0)
			)
			(min_thickness 0.25)
			(keepout
				(tracks allowed)
				(vias not_allowed)
				(pads allowed)
				(copperpour not_allowed)
				(footprints allowed)
			)
			(placement
				(enabled no)
				(sheetname "")
			)
			(fill
				(thermal_gap 0.5)
				(thermal_bridge_width 0.5)
				(island_removal_mode 0)
			)
			(polygon
				(pts
					(xy 108.8136 -12.4587) (xy 108.8136 -13.4493) (xy 108.3056 -13.4493) (xy 108.3056 -12.4587)
				)
			)
		)
		(zone
			(layer "F.Cu")
			(hatch none 0.5)
			(connect_pads
				(clearance 0)
			)
			(min_thickness 0.25)
			(keepout
				(tracks not_allowed)
				(vias allowed)
				(pads allowed)
				(copperpour not_allowed)
				(footprints allowed)
			)
			(placement
				(enabled no)
				(sheetname "")
			)
			(fill
				(thermal_gap 0.5)
				(thermal_bridge_width 0.5)
				(island_removal_mode 0)
			)
			(polygon
				(pts
					(xy 108.8136 -12.4587) (xy 108.8136 -13.4493) (xy 108.3056 -13.4493) (xy 108.3056 -12.4587)
				)
			)
		)
	)
	(footprint ""
		(layer "F.Cu")
		(at 24.007826 -87.841582 180)
		(property "Reference" "RF8"
			(at -0.8382 -0.67818 180)
			(unlocked yes)
			(layer "F.SilkS")
			(effects
				(font
					(size 0.4064 0.254)
					(thickness 0.1524)
				)
				(justify left)
			)
		)
		(property "Value" ""
			(at 0 0 180)
			(layer "F.Fab")
			(effects
				(font
					(size 1.27 1.27)
				)
			)
		)
		(duplicate_pad_numbers_are_jumpers no)
		(fp_poly
			(pts
				(xy -0.2794 -0.1016) (xy 0.2794 -0.1016) (xy 0.2794 0.9906) (xy -0.2794 0.9906)
			)
			(stroke
				(width 0)
				(type default)
			)
			(fill no)
			(layer "F.CrtYd")
		)
		(fp_line
			(start 0.2794 0.9906)
			(end 0.2794 -0.1016)
			(stroke
				(width 0.1)
				(type default)
			)
			(layer "F.Fab")
		)
		(fp_line
			(start 0.2794 -0.1016)
			(end -0.2794 -0.1016)
			(stroke
				(width 0.1)
				(type default)
			)
			(layer "F.Fab")
		)
		(fp_line
			(start -0.2794 0.9906)
			(end 0.2794 0.9906)
			(stroke
				(width 0.1)
				(type default)
			)
			(layer "F.Fab")
		)
		(fp_line
			(start -0.2794 -0.1016)
			(end -0.2794 0.9906)
			(stroke
				(width 0.1)
				(type default)
			)
			(layer "F.Fab")
		)
		(pad "1" smd rect
			(at 0 0 180)
			(size 0.508 0.508)
			(layers "F.Cu" "F.Mask" "F.Paste")
			(net "VR_PVCCIN_CPU1_AIREF2")
		)
		(pad "2" smd rect
			(at 0 0.889 180)
			(size 0.508 0.508)
			(layers "F.Cu" "F.Mask" "F.Paste")
			(net "ISENSE_PVCCIN_CPU1_PH2_IMON")
		)
		(zone
			(layer "F.Cu")
			(hatch none 0.5)
			(connect_pads
				(clearance 0)
			)
			(min_thickness 0.25)
			(keepout
				(tracks not_allowed)
				(vias allowed)
				(pads allowed)
				(copperpour not_allowed)
				(footprints allowed)
			)
			(placement
				(enabled no)
				(sheetname "")
			)
			(fill
				(thermal_gap 0.5)
				(thermal_bridge_width 0.5)
				(island_removal_mode 0)
			)
			(polygon
				(pts
					(xy 24.261826 -88.476582) (xy 23.753826 -88.476582) (xy 23.753826 -88.095582) (xy 24.261826 -88.095582)
				)
			)
		)
		(zone
			(layer "F.Cu")
			(hatch none 0.5)
			(connect_pads
				(clearance 0)
			)
			(min_thickness 0.25)
			(keepout
				(tracks allowed)
				(vias not_allowed)
				(pads allowed)
				(copperpour not_allowed)
				(footprints allowed)
			)
			(placement
				(enabled no)
				(sheetname "")
			)
			(fill
				(thermal_gap 0.5)
				(thermal_bridge_width 0.5)
				(island_removal_mode 0)
			)
			(polygon
				(pts
					(xy 24.261826 -88.095582) (xy 23.753826 -88.095582) (xy 23.753826 -88.476582) (xy 24.261826 -88.476582)
				)
			)
		)
	)
	(footprint ""
		(layer "F.Cu")
		(at 259.3848 -139.954 90)
		(property "Reference" "C5A20"
			(at 0 0 90)
			(layer "F.SilkS")
			(hide yes)
			(effects
				(font
					(size 1.27 1.27)
				)
			)
		)
		(property "Value" ""
			(at 0 0 90)
			(layer "F.Fab")
			(effects
				(font
					(size 1.27 1.27)
				)
			)
		)
		(duplicate_pad_numbers_are_jumpers no)
		(fp_rect
			(start -0.7239 -0.2159)
			(end 0.7239 1.9939)
			(stroke
				(width 0)
				(type default)
			)
			(fill no)
			(layer "F.CrtYd")
		)
		(fp_line
			(start 0.7239 -0.2159)
			(end -0.7239 -0.2159)
			(stroke
				(width 0.1)
				(type default)
			)
			(layer "F.Fab")
		)
		(fp_line
			(start -0.7239 -0.2159)
			(end -0.7239 1.9939)
			(stroke
				(width 0.1)
				(type default)
			)
			(layer "F.Fab")
		)
		(fp_line
			(start 0.7239 1.9939)
			(end 0.7239 -0.2159)
			(stroke
				(width 0.1)
				(type default)
			)
			(layer "F.Fab")
		)
		(fp_line
			(start -0.7239 1.9939)
			(end 0.7239 1.9939)
			(stroke
				(width 0.1)
				(type default)
			)
			(layer "F.Fab")
		)
		(pad "1" smd rect
			(at 0 0 90)
			(size 1.27 1.016)
			(layers "F.Cu" "F.Mask" "F.Paste")
			(net "PVDDQ_DEF")
		)
		(pad "2" smd rect
			(at 0 1.778 90)
			(size 1.27 1.016)
			(layers "F.Cu" "F.Mask" "F.Paste")
			(net "GND")
		)
		(zone
			(layer "F.Cu")
			(hatch none 0.5)
			(connect_pads
				(clearance 0)
			)
			(min_thickness 0.25)
			(keepout
				(tracks not_allowed)
				(vias allowed)
				(pads allowed)
				(copperpour not_allowed)
				(footprints allowed)
			)
			(placement
				(enabled no)
				(sheetname "")
			)
			(fill
				(thermal_gap 0.5)
				(thermal_bridge_width 0.5)
				(island_removal_mode 0)
			)
			(polygon
				(pts
					(xy 259.8928 -139.319) (xy 260.6548 -139.319) (xy 260.6548 -140.589) (xy 259.8928 -140.589)
				)
			)
		)
	)
	(footprint ""
		(layer "F.Cu")
		(at 198.925434 -73.295764 90)
		(property "Reference" "EU4D3"
			(at 3.334766 -1.669034 0)
			(unlocked yes)
			(layer "F.SilkS")
			(effects
				(font
					(size 0.7874 0.5842)
					(thickness 0.1524)
				)
			)
		)
		(property "Value" ""
			(at 0 0 90)
			(layer "F.Fab")
			(effects
				(font
					(size 1.27 1.27)
				)
			)
		)
		(duplicate_pad_numbers_are_jumpers no)
		(fp_line
			(start 2.9718 -3.5052)
			(end 2.9718 3.429)
			(stroke
				(width 0.1524)
				(type default)
			)
			(layer "F.SilkS")
		)
		(fp_line
			(start -3.0099 -3.5052)
			(end 2.9718 -3.5052)
			(stroke
				(width 0.1524)
				(type default)
			)
			(layer "F.SilkS")
		)
		(fp_line
			(start 2.9718 3.429)
			(end -3.0099 3.429)
			(stroke
				(width 0.1524)
				(type default)
			)
			(layer "F.SilkS")
		)
		(fp_line
			(start -3.0099 3.429)
			(end -3.0099 -3.5052)
			(stroke
				(width 0.1524)
				(type default)
			)
			(layer "F.SilkS")
		)
		(fp_circle
			(center -3.057398 -2.678684)
			(end -3.057398 -2.551684)
			(stroke
				(width 0.254)
				(type default)
			)
			(fill no)
			(layer "F.SilkS")
		)
		(fp_poly
			(pts
				(xy -2.9972 -3.4925) (xy -2.9972 -2.6924) (xy -2.1971 -3.4925)
			)
			(stroke
				(width 0)
				(type default)
			)
			(fill yes)
			(layer "F.SilkS")
		)
		(fp_poly
			(pts
				(xy -2.549906 -3.050032) (xy -2.549906 3.050032) (xy 2.549906 3.050032) (xy 2.549906 -3.050032)
			)
			(stroke
				(width 0)
				(type default)
			)
			(fill no)
			(layer "F.CrtYd")
		)
		(fp_line
			(start 2.549906 -3.050032)
			(end 2.549906 3.050032)
			(stroke
				(width 0.1)
				(type default)
			)
			(layer "F.Fab")
		)
		(fp_line
			(start -2.549906 -3.050032)
			(end 2.549906 -3.050032)
			(stroke
				(width 0.1)
				(type default)
			)
			(layer "F.Fab")
		)
		(fp_line
			(start 2.549906 3.050032)
			(end -2.549906 3.050032)
			(stroke
				(width 0.1)
				(type default)
			)
			(layer "F.Fab")
		)
		(fp_line
			(start -2.549906 3.050032)
			(end -2.549906 -3.050032)
			(stroke
				(width 0.1)
				(type default)
			)
			(layer "F.Fab")
		)
		(fp_circle
			(center -3.057398 -2.678684)
			(end -3.057398 -2.551684)
			(stroke
				(width 0.254)
				(type default)
			)
			(fill no)
			(layer "F.Fab")
		)
		(pad "1" smd rect
			(at -2.39522 -2.279904 90)
			(size 0.7112 0.254)
			(layers "F.Cu" "F.Mask" "F.Paste")
			(net "PVCCIN_CPU0")
		)
		(pad "2" smd rect
			(at -2.39522 -1.83007 90)
			(size 0.7112 0.254)
			(layers "F.Cu" "F.Mask" "F.Paste")
			(net "GND")
		)
		(pad "3" smd rect
			(at -2.39522 -1.379982 90)
			(size 0.7112 0.254)
			(layers "F.Cu" "F.Mask" "F.Paste")
			(net "VR_PVCCIN_CPU0_PH3_VCIN")
		)
		(pad "4" smd rect
			(at -2.39522 -0.929894 90)
			(size 0.7112 0.254)
			(layers "F.Cu" "F.Mask" "F.Paste")
			(net "P5V_STBY")
		)
		(pad "5" smd rect
			(at -2.39522 -0.48006 90)
			(size 0.7112 0.254)
			(layers "F.Cu" "F.Mask" "F.Paste")
			(net "GND")
		)
		(pad "6" smd rect
			(at -2.39522 -0.029972 90)
			(size 0.7112 0.254)
			(layers "F.Cu" "F.Mask" "F.Paste")
			(net "TP_PVCCIN_CPU0_PH3_GL_0")
		)
		(pad "7" smd custom
			(at 0.016764 1.145032 90)
			(size 0.53975 0.53975)
			(layers "F.Cu" "F.Mask" "F.Paste")
			(net "GND")
			(options
				(clearance outline)
				(anchor circle)
			)
			(primitives
				(gr_poly
					(pts
						(xy -2.7051 1.0795) (xy -2.7051 -0.3683) (xy -0.9271 -0.3683) (xy -0.9271 -1.0795) (xy 2.7051 -1.0795)
						(xy 2.7051 1.0795)
					)
					(width 0)
					(fill yes)
				)
			)
		)
		(pad "10" smd rect
			(at -0.008382 2.874772 90)
			(size 4.3434 0.6096)
			(layers "F.Cu" "F.Mask" "F.Paste")
			(net "VR_PVCCIN_CPU0_PHASE3")
		)
		(pad "25" smd rect
			(at 1.548384 -1.283208 90)
			(size 2.3368 2.0066)
			(layers "F.Cu" "F.Mask" "F.Paste")
			(net "VR_FET_SW_P12V_STBY_PVCCIN_CPU0")
		)
		(pad "30" smd rect
			(at 2.050034 -2.895092 90)
			(size 0.254 0.7112)
			(layers "F.Cu" "F.Mask" "F.Paste")
			(net "VR_FET_SW_P12V_STBY_PVCCIN_CPU0")
		)
		(pad "31" smd rect
			(at 1.599946 -2.895092 90)
			(size 0.254 0.7112)
			(layers "F.Cu" "F.Mask" "F.Paste")
			(net "Net_363")
		)
		(pad "32" smd rect
			(at 1.150112 -2.895092 90)
			(size 0.254 0.7112)
			(layers "F.Cu" "F.Mask" "F.Paste")
			(net "VR_PVCCIN_CPU0_PH3_PHASE")
		)
		(pad "33" smd rect
			(at 0.700024 -2.895092 90)
			(size 0.254 0.7112)
			(layers "F.Cu" "F.Mask" "F.Paste")
			(net "VR_PVCCIN_CPU0_PH3_BOOT_R")
		)
		(pad "34" smd rect
			(at 0.249936 -2.895092 90)
			(size 0.254 0.7112)
			(layers "F.Cu" "F.Mask" "F.Paste")
			(net "VR_PVCCIN_CPU0_PWM3")
		)
		(pad "35" smd rect
			(at -0.199898 -2.895092 90)
			(size 0.254 0.7112)
			(layers "F.Cu" "F.Mask" "F.Paste")
			(net "P5V_STBY")
		)
		(pad "36" smd rect
			(at -0.649986 -2.895092 90)
			(size 0.254 0.7112)
			(layers "F.Cu" "F.Mask" "F.Paste")
			(net "A_TSENSE_PVCCIN_CPU0")
		)
		(pad "37" smd rect
			(at -1.100074 -2.895092 90)
			(size 0.254 0.7112)
			(layers "F.Cu" "F.Mask" "F.Paste")
			(net "VR_PVCCIN_CPU0_PH3_OCSET")
		)
		(pad "38" smd rect
			(at -1.549908 -2.895092 90)
			(size 0.254 0.7112)
			(layers "F.Cu" "F.Mask" "F.Paste")
			(net "ISENSE_PVCCIN_CPU0_PH3_IMON")
		)
		(pad "39" smd rect
			(at -1.999996 -2.895092 90)
			(size 0.254 0.7112)
			(layers "F.Cu" "F.Mask" "F.Paste")
			(net "VR_PVCCIN_CPU0_AIREF3")
		)
		(pad "40" smd rect
			(at -0.871728 -1.283208 90)
			(size 1.8034 2.0066)
			(layers "F.Cu" "F.Mask" "F.Paste")
			(net "GND")
		)
		(pad "41" smd rect
			(at -1.533906 0.247904 90)
			(size 0.508 0.3556)
			(layers "F.Cu" "F.Mask" "F.Paste")
			(net "TP_PVCCIN_CPU0_PH3_GL_1")
		)
	)
)
